# TIMECARD (Time Appliance Project (Time Card)) — schematic netlist excerpt (pin names and nets, part order shuffled) for the footprints in the layout excerpt that follows; sources: Cadence DE-HDL packaged netlist, KiCad conversion of R4006-B0001-02_R01.brd

U18  FT4232HL_REEL_QFP64  FT4232HL-REEL  pkg QFP64_394_P0197_V1  page 24
  GND_8  = SG
  OSCI  = UNNAMED_524_CAPACITOR_I7_2
  OSCO  = UNNAMED_524_CAPACITOR_I10_2
  VPHY  = XP3R3V_VPHY
  GND_7  = SG
  REF  = UNNAMED_524_FT4232HLREELQFP64_6
  DM  = R_FT_USB_DM
  DP  = R_FT_USB_DP
  VPLL  = XP3R3V_VPLL
  AGND  = SG
  GND_6  = SG
  VCORE_3  = FT4232_VREGOUT
  TEST  = SG
  \reset*\  = UNNAMED_524_FT4232HLREELQFP64_7
  GND_5  = SG
  ADBUS0  = R_FT4232_TCK
  ADBUS1  = R_FT4232_TDI
  ADBUS2  = R_FT4232_TDO
  ADBUS3  = R_FT4232_TMS
  VCCIO_4  = XP3R3V_FT4232
  ADBUS4  = FT4232_MUX1_SEL
  ADBUS5  = FT4232_MUX2_SEL
  ADBUS6  = FT4232_MUX3_SEL
  ADBUS7  = UNNAMED_524_FT4232HLREELQFP64_I
  GND_4  = SG
  BDBUS0  = R_FT4232_I2C_SCL
  BDBUS1  = R_FT4232_I2C_SDA_OUT
  BDBUS2  = R_FT4232_I2C_SDA_IN
  BDBUS3  = UNNAMED_524_FT4232HLREELQFP64_1
  BDBUS4  = UNNAMED_524_FT4232HLREELQFP64_2
  VCCIO_3  = XP3R3V_FT4232
  BDBUS5  = UNNAMED_524_FT4232HLREELQFP64_3
  BDBUS6  = UNNAMED_524_FT4232HLREELQFP64_4
  BDBUS7  = UNNAMED_524_FT4232HLREELQFP64_5
  GND_3  = SG
  \suspend*\  = NC
  VCORE_2  = FT4232_VREGOUT
  CDBUS0  = R_FT4232_CHC_TX
  CDBUS1  = R_FT4232_CHC_RX
  CDBUS2  = NC
  CDBUS3  = NC
  VCCIO_2  = XP3R3V_FT4232
  CDBUS4  = NC
  CDBUS5  = NC
  CDBUS6  = NC
  CDBUS7  = NC
  GND_2  = SG
  DDBUS0  = R_FT4232_CHD_TX
  VREGOUT  = FT4232_VREGOUT
  VREGIN  = XP3R3V_FT4232
  GND_1  = SG
  DDBUS1  = R_FT4232_CHD_RX
  DDBUS2  = NC
  DDBUS3  = NC
  DDBUS4  = NC
  VCCIO_1  = XP3R3V_FT4232
  DDBUS5  = NC
  DDBUS6  = NC
  DDBUS7  = NC
  \pwren*\  = NC
  EEDATA  = FTDI_EE_DAT
  EECLK  = FTDI_EE_CLK
  EECS  = FTDI_EE_CS
  VCORE_1  = FT4232_VREGOUT

(kicad_pcb
	(version 20260206)
	(generator "pcbnew")
	(generator_version "10.0")
	(general
		(thickness 1.6)
		(legacy_teardrops no)
	)
	(paper "A4")
	(title_block
		(title "timecard-production-celestica-r4006 — R4006-B0001-02_R01.brd")
		(comment 1 "Time Appliance Project (Time Card) / footprint 538 of 1113 (U18), pads 1-46 of 64")
	)
	(layers
		(0 "F.Cu" signal "TOP")
		(4 "In1.Cu" signal "L02_GND1")
		(6 "In2.Cu" signal "L03_SIG1")
		(8 "In3.Cu" signal "L04_GND2")
		(10 "In4.Cu" signal "L05_VCC1")
		(12 "In5.Cu" signal "L06_VCC2")
		(14 "In6.Cu" signal "L07_GND3")
		(16 "In7.Cu" signal "L08_SIG2")
		(18 "In8.Cu" signal "L09_GND4")
		(2 "B.Cu" signal "BOTTOM")
		(9 "F.Adhes" user "F.Adhesive")
		(11 "B.Adhes" user "B.Adhesive")
		(13 "F.Paste" user "Package Geometry/Pastemask Top")
		(15 "B.Paste" user "Package Geometry/Pastemask Bottom")
		(5 "F.SilkS" user "Ref Des/Silkscreen Top")
		(7 "B.SilkS" user "Ref Des/Silkscreen Bottom")
		(1 "F.Mask" user "Board Geometry/Soldermask Top")
		(3 "B.Mask" user "Board Geometry/Soldermask Bottom")
		(17 "Dwgs.User" user "User.Drawings")
		(19 "Cmts.User" user "User.Comments")
		(21 "Eco1.User" user "User.Eco1")
		(23 "Eco2.User" user "User.Eco2")
		(25 "Edge.Cuts" user "Board Geometry/Outline")
		(27 "Margin" user)
		(31 "F.CrtYd" user "Package Geometry/Place Bound Top")
		(29 "B.CrtYd" user "Package Geometry/Place Bound Bottom")
		(35 "F.Fab" user "Ref Des/Assembly Top")
		(33 "B.Fab" user "Ref Des/Assembly Bottom")
	)
	(footprint ""
		(layer "F.Cu")
		(at 28.5242 -85.0646 -90)
		(property "Reference" "U18"
			(at -1.4224 -8.09117 90)
			(unlocked yes)
			(layer "F.SilkS")
			(effects
				(font
					(size 0.7874 0.5842)
					(thickness 0.1524)
				)
			)
		)
		(property "Value" ""
			(at 0 0 270)
			(layer "F.Fab")
			(effects
				(font
					(size 1.27 1.27)
				)
			)
		)
		(property "Device Type" "FT4232HL_REEL_QFP64-G223-10282A"
			(at -0.0127 7.86257 270)
			(unlocked yes)
			(layer "F.Fab")
			(hide yes)
			(effects
				(font
					(size 0.381 0.254)
					(thickness 0.000001)
				)
			)
		)
		(property "User Part Number" "PARTNUM*"
			(at 0.17018 8.41375 270)
			(unlocked yes)
			(layer "Cmts.User")
			(hide yes)
			(effects
				(font
					(size 0.381 0.254)
					(thickness 0.000001)
				)
			)
		)
		(duplicate_pad_numbers_are_jumpers no)
		(pad "1" smd rect
			(at -5.8166 -3.750056)
			(size 0.3048 1.6256)
			(layers "F.Cu" "F.Mask" "F.Paste")
			(net "SG")
		)
		(pad "2" smd rect
			(at -5.8166 -3.24993)
			(size 0.3048 1.6256)
			(layers "F.Cu" "F.Mask" "F.Paste")
			(net "UNNAMED_524_CAPACITOR_I7_2")
		)
		(pad "3" smd rect
			(at -5.8166 -2.750058)
			(size 0.3048 1.6256)
			(layers "F.Cu" "F.Mask" "F.Paste")
			(net "UNNAMED_524_CAPACITOR_I10_2")
		)
		(pad "4" smd rect
			(at -5.8166 -2.249932)
			(size 0.3048 1.6256)
			(layers "F.Cu" "F.Mask" "F.Paste")
			(net "XP3R3V_VPHY")
		)
		(pad "5" smd rect
			(at -5.8166 -1.75006)
			(size 0.3048 1.6256)
			(layers "F.Cu" "F.Mask" "F.Paste")
			(net "SG")
		)
		(pad "6" smd rect
			(at -5.8166 -1.249934)
			(size 0.3048 1.6256)
			(layers "F.Cu" "F.Mask" "F.Paste")
			(net "UNNAMED_524_FT4232HLREELQFP64_6")
		)
		(pad "7" smd rect
			(at -5.8166 -0.750062)
			(size 0.3048 1.6256)
			(layers "F.Cu" "F.Mask" "F.Paste")
			(net "R_FT_USB_DM")
		)
		(pad "8" smd rect
			(at -5.8166 -0.249936)
			(size 0.3048 1.6256)
			(layers "F.Cu" "F.Mask" "F.Paste")
			(net "R_FT_USB_DP")
		)
		(pad "9" smd rect
			(at -5.8166 0.249936)
			(size 0.3048 1.6256)
			(layers "F.Cu" "F.Mask" "F.Paste")
			(net "XP3R3V_VPLL")
		)
		(pad "10" smd rect
			(at -5.8166 0.750062)
			(size 0.3048 1.6256)
			(layers "F.Cu" "F.Mask" "F.Paste")
			(net "SG")
		)
		(pad "11" smd rect
			(at -5.8166 1.249934)
			(size 0.3048 1.6256)
			(layers "F.Cu" "F.Mask" "F.Paste")
			(net "SG")
		)
		(pad "12" smd rect
			(at -5.8166 1.75006)
			(size 0.3048 1.6256)
			(layers "F.Cu" "F.Mask" "F.Paste")
			(net "FT4232_VREGOUT")
		)
		(pad "13" smd rect
			(at -5.8166 2.249932)
			(size 0.3048 1.6256)
			(layers "F.Cu" "F.Mask" "F.Paste")
			(net "SG")
		)
		(pad "14" smd rect
			(at -5.8166 2.750058)
			(size 0.3048 1.6256)
			(layers "F.Cu" "F.Mask" "F.Paste")
			(net "UNNAMED_524_FT4232HLREELQFP64_7")
		)
		(pad "15" smd rect
			(at -5.8166 3.24993)
			(size 0.3048 1.6256)
			(layers "F.Cu" "F.Mask" "F.Paste")
			(net "SG")
		)
		(pad "16" smd rect
			(at -5.8166 3.750056)
			(size 0.3048 1.6256)
			(layers "F.Cu" "F.Mask" "F.Paste")
			(net "R_FT4232_TCK")
		)
		(pad "17" smd rect
			(at -3.750056 5.8166 90)
			(size 0.3048 1.6256)
			(layers "F.Cu" "F.Mask" "F.Paste")
			(net "R_FT4232_TDI")
		)
		(pad "18" smd rect
			(at -3.24993 5.8166 90)
			(size 0.3048 1.6256)
			(layers "F.Cu" "F.Mask" "F.Paste")
			(net "R_FT4232_TDO")
		)
		(pad "19" smd rect
			(at -2.750058 5.8166 90)
			(size 0.3048 1.6256)
			(layers "F.Cu" "F.Mask" "F.Paste")
			(net "R_FT4232_TMS")
		)
		(pad "20" smd rect
			(at -2.249932 5.8166 90)
			(size 0.3048 1.6256)
			(layers "F.Cu" "F.Mask" "F.Paste")
			(net "XP3R3V_FT4232")
		)
		(pad "21" smd rect
			(at -1.75006 5.8166 90)
			(size 0.3048 1.6256)
			(layers "F.Cu" "F.Mask" "F.Paste")
			(net "FT4232_MUX1_SEL")
		)
		(pad "22" smd rect
			(at -1.249934 5.8166 90)
			(size 0.3048 1.6256)
			(layers "F.Cu" "F.Mask" "F.Paste")
			(net "FT4232_MUX2_SEL")
		)
		(pad "23" smd rect
			(at -0.750062 5.8166 90)
			(size 0.3048 1.6256)
			(layers "F.Cu" "F.Mask" "F.Paste")
			(net "FT4232_MUX3_SEL")
		)
		(pad "24" smd rect
			(at -0.249936 5.8166 90)
			(size 0.3048 1.6256)
			(layers "F.Cu" "F.Mask" "F.Paste")
			(net "UNNAMED_524_FT4232HLREELQFP64_I")
		)
		(pad "25" smd rect
			(at 0.249936 5.8166 90)
			(size 0.3048 1.6256)
			(layers "F.Cu" "F.Mask" "F.Paste")
			(net "SG")
		)
		(pad "26" smd rect
			(at 0.750062 5.8166 90)
			(size 0.3048 1.6256)
			(layers "F.Cu" "F.Mask" "F.Paste")
			(net "R_FT4232_I2C_SCL")
		)
		(pad "27" smd rect
			(at 1.249934 5.8166 90)
			(size 0.3048 1.6256)
			(layers "F.Cu" "F.Mask" "F.Paste")
			(net "R_FT4232_I2C_SDA_OUT")
		)
		(pad "28" smd rect
			(at 1.75006 5.8166 90)
			(size 0.3048 1.6256)
			(layers "F.Cu" "F.Mask" "F.Paste")
			(net "R_FT4232_I2C_SDA_IN")
		)
		(pad "29" smd rect
			(at 2.249932 5.8166 90)
			(size 0.3048 1.6256)
			(layers "F.Cu" "F.Mask" "F.Paste")
			(net "UNNAMED_524_FT4232HLREELQFP64_1")
		)
		(pad "30" smd rect
			(at 2.750058 5.8166 90)
			(size 0.3048 1.6256)
			(layers "F.Cu" "F.Mask" "F.Paste")
			(net "UNNAMED_524_FT4232HLREELQFP64_2")
		)
		(pad "31" smd rect
			(at 3.24993 5.8166 90)
			(size 0.3048 1.6256)
			(layers "F.Cu" "F.Mask" "F.Paste")
			(net "XP3R3V_FT4232")
		)
		(pad "32" smd rect
			(at 3.750056 5.8166 90)
			(size 0.3048 1.6256)
			(layers "F.Cu" "F.Mask" "F.Paste")
			(net "UNNAMED_524_FT4232HLREELQFP64_3")
		)
		(pad "33" smd rect
			(at 5.8166 3.750056)
			(size 0.3048 1.6256)
			(layers "F.Cu" "F.Mask" "F.Paste")
			(net "UNNAMED_524_FT4232HLREELQFP64_4")
		)
		(pad "34" smd rect
			(at 5.8166 3.24993)
			(size 0.3048 1.6256)
			(layers "F.Cu" "F.Mask" "F.Paste")
			(net "UNNAMED_524_FT4232HLREELQFP64_5")
		)
		(pad "35" smd rect
			(at 5.8166 2.750058)
			(size 0.3048 1.6256)
			(layers "F.Cu" "F.Mask" "F.Paste")
			(net "SG")
		)
		(pad "36" smd rect
			(at 5.8166 2.249932)
			(size 0.3048 1.6256)
			(layers "F.Cu" "F.Mask" "F.Paste")
			(net "Net_789")
		)
		(pad "37" smd rect
			(at 5.8166 1.75006)
			(size 0.3048 1.6256)
			(layers "F.Cu" "F.Mask" "F.Paste")
			(net "FT4232_VREGOUT")
		)
		(pad "38" smd rect
			(at 5.8166 1.249934)
			(size 0.3048 1.6256)
			(layers "F.Cu" "F.Mask" "F.Paste")
			(net "R_FT4232_CHC_TX")
		)
		(pad "39" smd rect
			(at 5.8166 0.750062)
			(size 0.3048 1.6256)
			(layers "F.Cu" "F.Mask" "F.Paste")
			(net "R_FT4232_CHC_RX")
		)
		(pad "40" smd rect
			(at 5.8166 0.249936)
			(size 0.3048 1.6256)
			(layers "F.Cu" "F.Mask" "F.Paste")
			(net "Net_802")
		)
		(pad "41" smd rect
			(at 5.8166 -0.249936)
			(size 0.3048 1.6256)
			(layers "F.Cu" "F.Mask" "F.Paste")
			(net "Net_801")
		)
		(pad "42" smd rect
			(at 5.8166 -0.750062)
			(size 0.3048 1.6256)
			(layers "F.Cu" "F.Mask" "F.Paste")
			(net "XP3R3V_FT4232")
		)
		(pad "43" smd rect
			(at 5.8166 -1.249934)
			(size 0.3048 1.6256)
			(layers "F.Cu" "F.Mask" "F.Paste")
			(net "Net_800")
		)
		(pad "44" smd rect
			(at 5.8166 -1.75006)
			(size 0.3048 1.6256)
			(layers "F.Cu" "F.Mask" "F.Paste")
			(net "Net_799")
		)
		(pad "45" smd rect
			(at 5.8166 -2.249932)
			(size 0.3048 1.6256)
			(layers "F.Cu" "F.Mask" "F.Paste")
			(net "Net_798")
		)
		(pad "46" smd rect
			(at 5.8166 -2.750058)
			(size 0.3048 1.6256)
			(layers "F.Cu" "F.Mask" "F.Paste")
			(net "Net_797")
		)
	)
)
